# T6G (Grand Teton) — schematic netlist excerpt (pin names and nets, part order shuffled) for the footprints in the layout excerpt that follows; sources: Cadence DE-HDL packaged netlist, KiCad conversion of 04192023_DAF0TMB3IC0_F0TG_MB_C_brd_V02_OCP.brd

R2421  Q_RES  33.2 1% CHIP  pkg 0402LF  page 150 : A = SMB_VR_SENSOR_3V3AUX_SCL ; B = SMB_VR_3V3AUX_SCL_R0
R1160  Q_RES  0 5% CHIP  pkg 0402LF  page 161 : A = SMB_CPU0_SEC_R_SDA ; B = SMB_CPU0_SEC_SDA

(kicad_pcb
	(version 20260206)
	(generator "pcbnew")
	(generator_version "10.0")
	(general
		(thickness 1.6)
		(legacy_teardrops no)
	)
	(paper "A4")
	(title_block
		(title "04192023_DAF0TMB3IC0_F0TG_MB_C_brd_V02_OCP.brd")
		(comment 1 "Grand Teton / footprints 6215-6216 of 8354")
	)
	(layers
		(0 "F.Cu" signal "TOP")
		(4 "In1.Cu" signal "GND")
		(6 "In2.Cu" signal "IN1")
		(8 "In3.Cu" signal "GND1")
		(10 "In4.Cu" signal "IN2")
		(12 "In5.Cu" signal "GND2")
		(14 "In6.Cu" signal "IN3")
		(16 "In7.Cu" signal "GND3")
		(18 "In8.Cu" signal "VCC")
		(20 "In9.Cu" signal "VCC1")
		(22 "In10.Cu" signal "GND4")
		(24 "In11.Cu" signal "IN4")
		(26 "In12.Cu" signal "GND5")
		(28 "In13.Cu" signal "IN5")
		(30 "In14.Cu" signal "GND6")
		(32 "In15.Cu" signal "IN6")
		(34 "In16.Cu" signal "GND7")
		(2 "B.Cu" signal "BOTTOM")
		(9 "F.Adhes" user "F.Adhesive")
		(11 "B.Adhes" user "B.Adhesive")
		(13 "F.Paste" user "Package Geometry/Pastemask Top")
		(15 "B.Paste" user "Package Geometry/Pastemask Bottom")
		(5 "F.SilkS" user "Ref Des/Silkscreen Top")
		(7 "B.SilkS" user "Ref Des/Silkscreen Bottom")
		(1 "F.Mask" user "Board Geometry/Soldermask Top")
		(3 "B.Mask" user "Board Geometry/Soldermask Bottom")
		(17 "Dwgs.User" user "User.Drawings")
		(19 "Cmts.User" user "User.Comments")
		(21 "Eco1.User" user "User.Eco1")
		(23 "Eco2.User" user "User.Eco2")
		(25 "Edge.Cuts" user "Board Geometry/Outline")
		(27 "Margin" user)
		(31 "F.CrtYd" user "Package Geometry/Place Bound Top")
		(29 "B.CrtYd" user "Package Geometry/Place Bound Bottom")
		(35 "F.Fab" user "Ref Des/Assembly Top")
		(33 "B.Fab" user "Ref Des/Assembly Bottom")
	)
	(footprint ""
		(layer "B.Cu")
		(at 177.264822 -10.1473 -90)
		(property "Reference" "R2421"
			(at 0 0 90)
			(layer "B.SilkS")
			(hide yes)
			(effects
				(font
					(size 1.27 1.27)
				)
				(justify mirror)
			)
		)
		(property "Value" ""
			(at 0 0 90)
			(layer "B.Fab")
			(effects
				(font
					(size 1.27 1.27)
				)
				(justify mirror)
			)
		)
		(duplicate_pad_numbers_are_jumpers no)
		(fp_line
			(start -0.7874 0.4064)
			(end 0.7874 0.4064)
			(stroke
				(width 0.1524)
				(type default)
			)
			(layer "B.SilkS")
		)
		(fp_line
			(start 0.7874 0.4064)
			(end 0.7874 -0.4064)
			(stroke
				(width 0.1524)
				(type default)
			)
			(layer "B.SilkS")
		)
		(fp_line
			(start -0.7874 -0.4064)
			(end -0.7874 0.4064)
			(stroke
				(width 0.1524)
				(type default)
			)
			(layer "B.SilkS")
		)
		(fp_line
			(start 0.7874 -0.4064)
			(end -0.7874 -0.4064)
			(stroke
				(width 0.1524)
				(type default)
			)
			(layer "B.SilkS")
		)
		(fp_line
			(start -0.67945 0.3048)
			(end -0.120396 0.3048)
			(stroke
				(width 0.1)
				(type default)
			)
			(layer "B.Fab")
		)
		(fp_line
			(start -0.120396 0.3048)
			(end -0.120396 0.2794)
			(stroke
				(width 0.1)
				(type default)
			)
			(layer "B.Fab")
		)
		(fp_line
			(start 0.12065 0.3048)
			(end 0.67945 0.3048)
			(stroke
				(width 0.1)
				(type default)
			)
			(layer "B.Fab")
		)
		(fp_line
			(start 0.67945 0.3048)
			(end 0.67945 -0.305054)
			(stroke
				(width 0.1)
				(type default)
			)
			(layer "B.Fab")
		)
		(fp_line
			(start -0.120396 0.2794)
			(end 0.12065 0.2794)
			(stroke
				(width 0.1)
				(type default)
			)
			(layer "B.Fab")
		)
		(fp_line
			(start 0.12065 0.2794)
			(end 0.12065 0.3048)
			(stroke
				(width 0.1)
				(type default)
			)
			(layer "B.Fab")
		)
		(fp_line
			(start -0.12065 -0.2794)
			(end -0.12065 -0.3048)
			(stroke
				(width 0.1)
				(type default)
			)
			(layer "B.Fab")
		)
		(fp_line
			(start 0.12065 -0.2794)
			(end -0.12065 -0.2794)
			(stroke
				(width 0.1)
				(type default)
			)
			(layer "B.Fab")
		)
		(fp_line
			(start -0.67945 -0.3048)
			(end -0.67945 0.3048)
			(stroke
				(width 0.1)
				(type default)
			)
			(layer "B.Fab")
		)
		(fp_line
			(start -0.12065 -0.3048)
			(end -0.67945 -0.3048)
			(stroke
				(width 0.1)
				(type default)
			)
			(layer "B.Fab")
		)
		(fp_line
			(start 0.12065 -0.305054)
			(end 0.12065 -0.2794)
			(stroke
				(width 0.1)
				(type default)
			)
			(layer "B.Fab")
		)
		(fp_line
			(start 0.67945 -0.305054)
			(end 0.12065 -0.305054)
			(stroke
				(width 0.1)
				(type default)
			)
			(layer "B.Fab")
		)
		(pad "1" smd circle
			(at 0.40005 0 90)
			(size 0 0)
			(layers "B.Cu" "B.Mask" "B.Paste")
			(net "SMB_VR_SENSOR_3V3AUX_SCL")
		)
		(pad "2" smd circle
			(at -0.40005 0 90)
			(size 0 0)
			(layers "B.Cu" "B.Mask" "B.Paste")
			(net "SMB_VR_3V3AUX_SCL_R0")
		)
	)
	(footprint ""
		(layer "B.Cu")
		(at 240.411 -234.061 90)
		(property "Reference" "R1160"
			(at 0 0 90)
			(layer "B.SilkS")
			(hide yes)
			(effects
				(font
					(size 1.27 1.27)
				)
				(justify mirror)
			)
		)
		(property "Value" ""
			(at 0 0 90)
			(layer "B.Fab")
			(effects
				(font
					(size 1.27 1.27)
				)
				(justify mirror)
			)
		)
		(duplicate_pad_numbers_are_jumpers no)
		(fp_line
			(start 0.7874 -0.4064)
			(end -0.7874 -0.4064)
			(stroke
				(width 0.1524)
				(type default)
			)
			(layer "B.SilkS")
		)
		(fp_line
			(start -0.7874 -0.4064)
			(end -0.7874 0.4064)
			(stroke
				(width 0.1524)
				(type default)
			)
			(layer "B.SilkS")
		)
		(fp_line
			(start 0.7874 0.4064)
			(end 0.7874 -0.4064)
			(stroke
				(width 0.1524)
				(type default)
			)
			(layer "B.SilkS")
		)
		(fp_line
			(start -0.7874 0.4064)
			(end 0.7874 0.4064)
			(stroke
				(width 0.1524)
				(type default)
			)
			(layer "B.SilkS")
		)
		(fp_line
			(start 0.67945 -0.305054)
			(end 0.12065 -0.305054)
			(stroke
				(width 0.1)
				(type default)
			)
			(layer "B.Fab")
		)
		(fp_line
			(start 0.12065 -0.305054)
			(end 0.12065 -0.2794)
			(stroke
				(width 0.1)
				(type default)
			)
			(layer "B.Fab")
		)
		(fp_line
			(start -0.12065 -0.3048)
			(end -0.67945 -0.3048)
			(stroke
				(width 0.1)
				(type default)
			)
			(layer "B.Fab")
		)
		(fp_line
			(start -0.67945 -0.3048)
			(end -0.67945 0.3048)
			(stroke
				(width 0.1)
				(type default)
			)
			(layer "B.Fab")
		)
		(fp_line
			(start 0.12065 -0.2794)
			(end -0.12065 -0.2794)
			(stroke
				(width 0.1)
				(type default)
			)
			(layer "B.Fab")
		)
		(fp_line
			(start -0.12065 -0.2794)
			(end -0.12065 -0.3048)
			(stroke
				(width 0.1)
				(type default)
			)
			(layer "B.Fab")
		)
		(fp_line
			(start 0.12065 0.2794)
			(end 0.12065 0.3048)
			(stroke
				(width 0.1)
				(type default)
			)
			(layer "B.Fab")
		)
		(fp_line
			(start -0.120396 0.2794)
			(end 0.12065 0.2794)
			(stroke
				(width 0.1)
				(type default)
			)
			(layer "B.Fab")
		)
		(fp_line
			(start 0.67945 0.3048)
			(end 0.67945 -0.305054)
			(stroke
				(width 0.1)
				(type default)
			)
			(layer "B.Fab")
		)
		(fp_line
			(start 0.12065 0.3048)
			(end 0.67945 0.3048)
			(stroke
				(width 0.1)
				(type default)
			)
			(layer "B.Fab")
		)
		(fp_line
			(start -0.120396 0.3048)
			(end -0.120396 0.2794)
			(stroke
				(width 0.1)
				(type default)
			)
			(layer "B.Fab")
		)
		(fp_line
			(start -0.67945 0.3048)
			(end -0.120396 0.3048)
			(stroke
				(width 0.1)
				(type default)
			)
			(layer "B.Fab")
		)
		(pad "1" smd circle
			(at 0.40005 0 270)
			(size 0 0)
			(layers "B.Cu" "B.Mask" "B.Paste")
			(net "SMB_CPU0_SEC_R_SDA")
		)
		(pad "2" smd circle
			(at -0.40005 0 270)
			(size 0 0)
			(layers "B.Cu" "B.Mask" "B.Paste")
			(net "SMB_CPU0_SEC_SDA")
		)
	)
)
